(kicad_pcb
	(version 20260206)
	(generator "pcbnew")
	(generator_version "10.0")
	(general
		(thickness 1.6)
		(legacy_teardrops no)
	)
	(paper "A4")
	(title_block
		(title "01162023_DA0F0TEBIF0_F0T_Expander_BD_F_brd_V02_OCP.brd")
		(comment 1 "Grand Teton / footprint 5622 of 9728 (PEX2), pads 1654-1767 of 2397")
	)
	(layers
		(0 "F.Cu" signal "TOP")
		(4 "In1.Cu" signal "GND")
		(6 "In2.Cu" signal "VCC")
		(8 "In3.Cu" signal "VCC1")
		(10 "In4.Cu" signal "GND1")
		(12 "In5.Cu" signal "IN1")
		(14 "In6.Cu" signal "GND2")
		(16 "In7.Cu" signal "IN2")
		(18 "In8.Cu" signal "GND3")
		(20 "In9.Cu" signal "IN3")
		(22 "In10.Cu" signal "GND4")
		(24 "In11.Cu" signal "IN4")
		(26 "In12.Cu" signal "GND5")
		(28 "In13.Cu" signal "IN5")
		(30 "In14.Cu" signal "GND6")
		(32 "In15.Cu" signal "IN6")
		(34 "In16.Cu" signal "GND7")
		(2 "B.Cu" signal "BOTTOM")
		(9 "F.Adhes" user "F.Adhesive")
		(11 "B.Adhes" user "B.Adhesive")
		(13 "F.Paste" user "Package Geometry/Pastemask Top")
		(15 "B.Paste" user "Package Geometry/Pastemask Bottom")
		(5 "F.SilkS" user "Ref Des/Silkscreen Top")
		(7 "B.SilkS" user "Ref Des/Silkscreen Bottom")
		(1 "F.Mask" user "Board Geometry/Soldermask Top")
		(3 "B.Mask" user "Board Geometry/Soldermask Bottom")
		(17 "Dwgs.User" user "User.Drawings")
		(19 "Cmts.User" user "User.Comments")
		(21 "Eco1.User" user "User.Eco1")
		(23 "Eco2.User" user "User.Eco2")
		(25 "Edge.Cuts" user "Board Geometry/Outline")
		(27 "Margin" user)
		(31 "F.CrtYd" user "Package Geometry/Place Bound Top")
		(29 "B.CrtYd" user "Package Geometry/Place Bound Bottom")
		(35 "F.Fab" user "Ref Des/Assembly Top")
		(33 "B.Fab" user "Ref Des/Assembly Bottom")
	)
	(footprint ""
		(layer "F.Cu")
		(at 291.84981 -295.89984)
		(property "Reference" "PEX2"
			(at -3.35153 35.56762 0)
			(unlocked yes)
			(layer "F.SilkS")
			(effects
				(font
					(size 2.032 1.524)
					(thickness 0.1524)
				)
				(justify left)
			)
		)
		(property "Value" ""
			(at 0 0 0)
			(layer "F.Fab")
			(effects
				(font
					(size 1.27 1.27)
				)
			)
		)
		(duplicate_pad_numbers_are_jumpers no)
		(pad "E41" smd circle
			(at 15.200122 -18.999962)
			(size 0.4572 0.4572)
			(layers "F.Cu" "F.Mask" "F.Paste")
			(net "GND")
		)
		(pad "E42" smd circle
			(at 16.150082 -18.999962)
			(size 0.4572 0.4572)
			(layers "F.Cu" "F.Mask" "F.Paste")
			(net "GND")
		)
		(pad "E43" smd circle
			(at 17.100042 -18.999962)
			(size 0.4572 0.4572)
			(layers "F.Cu" "F.Mask" "F.Paste")
			(net "GND")
		)
		(pad "E44" smd circle
			(at 18.050002 -18.999962)
			(size 0.4572 0.4572)
			(layers "F.Cu" "F.Mask" "F.Paste")
			(net "GND")
		)
		(pad "E45" smd circle
			(at 18.999962 -18.999962)
			(size 0.4572 0.4572)
			(layers "F.Cu" "F.Mask" "F.Paste")
			(net "GND")
		)
		(pad "E46" smd circle
			(at 19.949922 -18.999962)
			(size 0.4572 0.4572)
			(layers "F.Cu" "F.Mask" "F.Paste")
			(net "GND")
		)
		(pad "E47" smd circle
			(at 20.899882 -18.999962)
			(size 0.4572 0.4572)
			(layers "F.Cu" "F.Mask" "F.Paste")
			(net "GND")
		)
		(pad "E48" smd circle
			(at 21.850096 -18.999962)
			(size 0.4572 0.4572)
			(layers "F.Cu" "F.Mask" "F.Paste")
			(net "P5E_PEX2_STN4_TX_DP<71>")
		)
		(pad "E49" smd circle
			(at 22.800056 -18.999962)
			(size 0.4572 0.4572)
			(layers "F.Cu" "F.Mask" "F.Paste")
			(net "P5E_PEX2_STN4_TX_DN<71>")
		)
		(pad "F1" smd circle
			(at -22.800056 -18.050002)
			(size 0.4572 0.4572)
			(layers "F.Cu" "F.Mask" "F.Paste")
			(net "GND")
		)
		(pad "F2" smd circle
			(at -21.850096 -18.050002)
			(size 0.4572 0.4572)
			(layers "F.Cu" "F.Mask" "F.Paste")
			(net "GND")
		)
		(pad "F3" smd circle
			(at -20.899882 -18.050002)
			(size 0.4572 0.4572)
			(layers "F.Cu" "F.Mask" "F.Paste")
			(net "P5E_PEX2_STN7_TX_DN<123>")
		)
		(pad "F4" smd circle
			(at -19.949922 -18.050002)
			(size 0.4572 0.4572)
			(layers "F.Cu" "F.Mask" "F.Paste")
			(net "GND")
		)
		(pad "F5" smd circle
			(at -18.999962 -18.050002)
			(size 0.4572 0.4572)
			(layers "F.Cu" "F.Mask" "F.Paste")
			(net "P5E_PEX2_STN7_TX_DN<125>")
		)
		(pad "F6" smd circle
			(at -18.050002 -18.050002)
			(size 0.4572 0.4572)
			(layers "F.Cu" "F.Mask" "F.Paste")
			(net "GND")
		)
		(pad "F7" smd circle
			(at -17.100042 -18.050002)
			(size 0.4572 0.4572)
			(layers "F.Cu" "F.Mask" "F.Paste")
			(net "P5E_PEX2_STN7_TX_DN<127>")
		)
		(pad "F8" smd circle
			(at -16.150082 -18.050002)
			(size 0.4572 0.4572)
			(layers "F.Cu" "F.Mask" "F.Paste")
			(net "GND")
		)
		(pad "F9" smd circle
			(at -15.200122 -18.050002)
			(size 0.4572 0.4572)
			(layers "F.Cu" "F.Mask" "F.Paste")
			(net "P5E_PEX2_STN6_TX_DN<110>")
		)
		(pad "F10" smd circle
			(at -14.249908 -18.050002)
			(size 0.4572 0.4572)
			(layers "F.Cu" "F.Mask" "F.Paste")
			(net "GND")
		)
		(pad "F11" smd circle
			(at -13.299948 -18.050002)
			(size 0.4572 0.4572)
			(layers "F.Cu" "F.Mask" "F.Paste")
			(net "P5E_PEX2_STN6_TX_DN<108>")
		)
		(pad "F12" smd circle
			(at -12.349988 -18.050002)
			(size 0.4572 0.4572)
			(layers "F.Cu" "F.Mask" "F.Paste")
			(net "GND")
		)
		(pad "F13" smd circle
			(at -11.400028 -18.050002)
			(size 0.4572 0.4572)
			(layers "F.Cu" "F.Mask" "F.Paste")
			(net "P5E_PEX2_STN6_TX_DN<106>")
		)
		(pad "F14" smd circle
			(at -10.450068 -18.050002)
			(size 0.4572 0.4572)
			(layers "F.Cu" "F.Mask" "F.Paste")
			(net "GND")
		)
		(pad "F15" smd circle
			(at -9.500108 -18.050002)
			(size 0.4572 0.4572)
			(layers "F.Cu" "F.Mask" "F.Paste")
			(net "P5E_PEX2_STN6_TX_DN<104>")
		)
		(pad "F16" smd circle
			(at -8.549894 -18.050002)
			(size 0.4572 0.4572)
			(layers "F.Cu" "F.Mask" "F.Paste")
			(net "GND")
		)
		(pad "F17" smd circle
			(at -7.599934 -18.050002)
			(size 0.4572 0.4572)
			(layers "F.Cu" "F.Mask" "F.Paste")
			(net "P5E_PEX2_STN6_TX_DN<102>")
		)
		(pad "F18" smd circle
			(at -6.649974 -18.050002)
			(size 0.4572 0.4572)
			(layers "F.Cu" "F.Mask" "F.Paste")
			(net "GND")
		)
		(pad "F19" smd circle
			(at -5.700014 -18.050002)
			(size 0.4572 0.4572)
			(layers "F.Cu" "F.Mask" "F.Paste")
			(net "P5E_PEX2_STN6_TX_DN<100>")
		)
		(pad "F20" smd circle
			(at -4.750054 -18.050002)
			(size 0.4572 0.4572)
			(layers "F.Cu" "F.Mask" "F.Paste")
			(net "GND")
		)
		(pad "F21" smd circle
			(at -3.800094 -18.050002)
			(size 0.4572 0.4572)
			(layers "F.Cu" "F.Mask" "F.Paste")
			(net "P5E_PEX2_STN6_TX_DN<98>")
		)
		(pad "F22" smd circle
			(at -2.84988 -18.050002)
			(size 0.4572 0.4572)
			(layers "F.Cu" "F.Mask" "F.Paste")
			(net "GND")
		)
		(pad "F23" smd circle
			(at -1.89992 -18.050002)
			(size 0.4572 0.4572)
			(layers "F.Cu" "F.Mask" "F.Paste")
			(net "P5E_PEX2_STN6_TX_DN<96>")
		)
		(pad "F24" smd circle
			(at -0.94996 -18.050002)
			(size 0.4572 0.4572)
			(layers "F.Cu" "F.Mask" "F.Paste")
			(net "GND")
		)
		(pad "F25" smd circle
			(at 0 -18.050002)
			(size 0.4572 0.4572)
			(layers "F.Cu" "F.Mask" "F.Paste")
			(net "P5E_PEX2_STN5_TX_DN<81>")
		)
		(pad "F26" smd circle
			(at 0.94996 -18.050002)
			(size 0.4572 0.4572)
			(layers "F.Cu" "F.Mask" "F.Paste")
			(net "GND")
		)
		(pad "F27" smd circle
			(at 1.89992 -18.050002)
			(size 0.4572 0.4572)
			(layers "F.Cu" "F.Mask" "F.Paste")
			(net "P5E_PEX2_STN5_TX_DN<83>")
		)
		(pad "F28" smd circle
			(at 2.84988 -18.050002)
			(size 0.4572 0.4572)
			(layers "F.Cu" "F.Mask" "F.Paste")
			(net "GND")
		)
		(pad "F29" smd circle
			(at 3.800094 -18.050002)
			(size 0.4572 0.4572)
			(layers "F.Cu" "F.Mask" "F.Paste")
			(net "P5E_PEX2_STN5_TX_DN<85>")
		)
		(pad "F30" smd circle
			(at 4.750054 -18.050002)
			(size 0.4572 0.4572)
			(layers "F.Cu" "F.Mask" "F.Paste")
			(net "GND")
		)
		(pad "F31" smd circle
			(at 5.700014 -18.050002)
			(size 0.4572 0.4572)
			(layers "F.Cu" "F.Mask" "F.Paste")
			(net "P5E_PEX2_STN5_TX_DN<87>")
		)
		(pad "F32" smd circle
			(at 6.649974 -18.050002)
			(size 0.4572 0.4572)
			(layers "F.Cu" "F.Mask" "F.Paste")
			(net "GND")
		)
		(pad "F33" smd circle
			(at 7.599934 -18.050002)
			(size 0.4572 0.4572)
			(layers "F.Cu" "F.Mask" "F.Paste")
			(net "P5E_PEX2_STN5_TX_DN<89>")
		)
		(pad "F34" smd circle
			(at 8.549894 -18.050002)
			(size 0.4572 0.4572)
			(layers "F.Cu" "F.Mask" "F.Paste")
			(net "GND")
		)
		(pad "F35" smd circle
			(at 9.500108 -18.050002)
			(size 0.4572 0.4572)
			(layers "F.Cu" "F.Mask" "F.Paste")
			(net "P5E_PEX2_STN5_TX_DN<91>")
		)
		(pad "F36" smd circle
			(at 10.450068 -18.050002)
			(size 0.4572 0.4572)
			(layers "F.Cu" "F.Mask" "F.Paste")
			(net "GND")
		)
		(pad "F37" smd circle
			(at 11.400028 -18.050002)
			(size 0.4572 0.4572)
			(layers "F.Cu" "F.Mask" "F.Paste")
			(net "P5E_PEX2_STN5_TX_DN<93>")
		)
		(pad "F38" smd circle
			(at 12.349988 -18.050002)
			(size 0.4572 0.4572)
			(layers "F.Cu" "F.Mask" "F.Paste")
			(net "GND")
		)
		(pad "F39" smd circle
			(at 13.299948 -18.050002)
			(size 0.4572 0.4572)
			(layers "F.Cu" "F.Mask" "F.Paste")
			(net "P5E_PEX2_STN5_TX_DN<95>")
		)
		(pad "F40" smd circle
			(at 14.249908 -18.050002)
			(size 0.4572 0.4572)
			(layers "F.Cu" "F.Mask" "F.Paste")
			(net "GND")
		)
		(pad "F41" smd circle
			(at 15.200122 -18.050002)
			(size 0.4572 0.4572)
			(layers "F.Cu" "F.Mask" "F.Paste")
			(net "P5E_PEX2_STN4_TX_DN<78>")
		)
		(pad "F42" smd circle
			(at 16.150082 -18.050002)
			(size 0.4572 0.4572)
			(layers "F.Cu" "F.Mask" "F.Paste")
			(net "GND")
		)
		(pad "F43" smd circle
			(at 17.100042 -18.050002)
			(size 0.4572 0.4572)
			(layers "F.Cu" "F.Mask" "F.Paste")
			(net "P5E_PEX2_STN4_TX_DN<76>")
		)
		(pad "F44" smd circle
			(at 18.050002 -18.050002)
			(size 0.4572 0.4572)
			(layers "F.Cu" "F.Mask" "F.Paste")
			(net "GND")
		)
		(pad "F45" smd circle
			(at 18.999962 -18.050002)
			(size 0.4572 0.4572)
			(layers "F.Cu" "F.Mask" "F.Paste")
			(net "P5E_PEX2_STN4_TX_DN<74>")
		)
		(pad "F46" smd circle
			(at 19.949922 -18.050002)
			(size 0.4572 0.4572)
			(layers "F.Cu" "F.Mask" "F.Paste")
			(net "GND")
		)
		(pad "F47" smd circle
			(at 20.899882 -18.050002)
			(size 0.4572 0.4572)
			(layers "F.Cu" "F.Mask" "F.Paste")
			(net "P5E_PEX2_STN4_TX_DN<72>")
		)
		(pad "F48" smd circle
			(at 21.850096 -18.050002)
			(size 0.4572 0.4572)
			(layers "F.Cu" "F.Mask" "F.Paste")
			(net "GND")
		)
		(pad "F49" smd circle
			(at 22.800056 -18.050002)
			(size 0.4572 0.4572)
			(layers "F.Cu" "F.Mask" "F.Paste")
			(net "GND")
		)
		(pad "G1" smd circle
			(at -22.800056 -17.100042)
			(size 0.4572 0.4572)
			(layers "F.Cu" "F.Mask" "F.Paste")
			(net "GND")
		)
		(pad "G2" smd circle
			(at -21.850096 -17.100042)
			(size 0.4572 0.4572)
			(layers "F.Cu" "F.Mask" "F.Paste")
			(net "GND")
		)
		(pad "G3" smd circle
			(at -20.899882 -17.100042)
			(size 0.4572 0.4572)
			(layers "F.Cu" "F.Mask" "F.Paste")
			(net "P5E_PEX2_STN7_TX_DP<123>")
		)
		(pad "G4" smd circle
			(at -19.949922 -17.100042)
			(size 0.4572 0.4572)
			(layers "F.Cu" "F.Mask" "F.Paste")
			(net "GND")
		)
		(pad "G5" smd circle
			(at -18.999962 -17.100042)
			(size 0.4572 0.4572)
			(layers "F.Cu" "F.Mask" "F.Paste")
			(net "P5E_PEX2_STN7_TX_DP<125>")
		)
		(pad "G6" smd circle
			(at -18.050002 -17.100042)
			(size 0.4572 0.4572)
			(layers "F.Cu" "F.Mask" "F.Paste")
			(net "GND")
		)
		(pad "G7" smd circle
			(at -17.100042 -17.100042)
			(size 0.4572 0.4572)
			(layers "F.Cu" "F.Mask" "F.Paste")
			(net "P5E_PEX2_STN7_TX_DP<127>")
		)
		(pad "G8" smd circle
			(at -16.150082 -17.100042)
			(size 0.4572 0.4572)
			(layers "F.Cu" "F.Mask" "F.Paste")
			(net "GND")
		)
		(pad "G9" smd circle
			(at -15.200122 -17.100042)
			(size 0.4572 0.4572)
			(layers "F.Cu" "F.Mask" "F.Paste")
			(net "P5E_PEX2_STN6_TX_DP<110>")
		)
		(pad "G10" smd circle
			(at -14.249908 -17.100042)
			(size 0.4572 0.4572)
			(layers "F.Cu" "F.Mask" "F.Paste")
			(net "GND")
		)
		(pad "G11" smd circle
			(at -13.299948 -17.100042)
			(size 0.4572 0.4572)
			(layers "F.Cu" "F.Mask" "F.Paste")
			(net "P5E_PEX2_STN6_TX_DP<108>")
		)
		(pad "G12" smd circle
			(at -12.349988 -17.100042)
			(size 0.4572 0.4572)
			(layers "F.Cu" "F.Mask" "F.Paste")
			(net "GND")
		)
		(pad "G13" smd circle
			(at -11.400028 -17.100042)
			(size 0.4572 0.4572)
			(layers "F.Cu" "F.Mask" "F.Paste")
			(net "P5E_PEX2_STN6_TX_DP<106>")
		)
		(pad "G14" smd circle
			(at -10.450068 -17.100042)
			(size 0.4572 0.4572)
			(layers "F.Cu" "F.Mask" "F.Paste")
			(net "GND")
		)
		(pad "G15" smd circle
			(at -9.500108 -17.100042)
			(size 0.4572 0.4572)
			(layers "F.Cu" "F.Mask" "F.Paste")
			(net "P5E_PEX2_STN6_TX_DP<104>")
		)
		(pad "G16" smd circle
			(at -8.549894 -17.100042)
			(size 0.4572 0.4572)
			(layers "F.Cu" "F.Mask" "F.Paste")
			(net "GND")
		)
		(pad "G17" smd circle
			(at -7.599934 -17.100042)
			(size 0.4572 0.4572)
			(layers "F.Cu" "F.Mask" "F.Paste")
			(net "P5E_PEX2_STN6_TX_DP<102>")
		)
		(pad "G18" smd circle
			(at -6.649974 -17.100042)
			(size 0.4572 0.4572)
			(layers "F.Cu" "F.Mask" "F.Paste")
			(net "GND")
		)
		(pad "G19" smd circle
			(at -5.700014 -17.100042)
			(size 0.4572 0.4572)
			(layers "F.Cu" "F.Mask" "F.Paste")
			(net "P5E_PEX2_STN6_TX_DP<100>")
		)
		(pad "G20" smd circle
			(at -4.750054 -17.100042)
			(size 0.4572 0.4572)
			(layers "F.Cu" "F.Mask" "F.Paste")
			(net "GND")
		)
		(pad "G21" smd circle
			(at -3.800094 -17.100042)
			(size 0.4572 0.4572)
			(layers "F.Cu" "F.Mask" "F.Paste")
			(net "P5E_PEX2_STN6_TX_DP<98>")
		)
		(pad "G22" smd circle
			(at -2.84988 -17.100042)
			(size 0.4572 0.4572)
			(layers "F.Cu" "F.Mask" "F.Paste")
			(net "GND")
		)
		(pad "G23" smd circle
			(at -1.89992 -17.100042)
			(size 0.4572 0.4572)
			(layers "F.Cu" "F.Mask" "F.Paste")
			(net "P5E_PEX2_STN6_TX_DP<96>")
		)
		(pad "G24" smd circle
			(at -0.94996 -17.100042)
			(size 0.4572 0.4572)
			(layers "F.Cu" "F.Mask" "F.Paste")
			(net "GND")
		)
		(pad "G25" smd circle
			(at 0 -17.100042)
			(size 0.4572 0.4572)
			(layers "F.Cu" "F.Mask" "F.Paste")
			(net "P5E_PEX2_STN5_TX_DP<81>")
		)
		(pad "G26" smd circle
			(at 0.94996 -17.100042)
			(size 0.4572 0.4572)
			(layers "F.Cu" "F.Mask" "F.Paste")
			(net "GND")
		)
		(pad "G27" smd circle
			(at 1.89992 -17.100042)
			(size 0.4572 0.4572)
			(layers "F.Cu" "F.Mask" "F.Paste")
			(net "P5E_PEX2_STN5_TX_DP<83>")
		)
		(pad "G28" smd circle
			(at 2.84988 -17.100042)
			(size 0.4572 0.4572)
			(layers "F.Cu" "F.Mask" "F.Paste")
			(net "GND")
		)
		(pad "G29" smd circle
			(at 3.800094 -17.100042)
			(size 0.4572 0.4572)
			(layers "F.Cu" "F.Mask" "F.Paste")
			(net "P5E_PEX2_STN5_TX_DP<85>")
		)
		(pad "G30" smd circle
			(at 4.750054 -17.100042)
			(size 0.4572 0.4572)
			(layers "F.Cu" "F.Mask" "F.Paste")
			(net "GND")
		)
		(pad "G31" smd circle
			(at 5.700014 -17.100042)
			(size 0.4572 0.4572)
			(layers "F.Cu" "F.Mask" "F.Paste")
			(net "P5E_PEX2_STN5_TX_DP<87>")
		)
		(pad "G32" smd circle
			(at 6.649974 -17.100042)
			(size 0.4572 0.4572)
			(layers "F.Cu" "F.Mask" "F.Paste")
			(net "GND")
		)
		(pad "G33" smd circle
			(at 7.599934 -17.100042)
			(size 0.4572 0.4572)
			(layers "F.Cu" "F.Mask" "F.Paste")
			(net "P5E_PEX2_STN5_TX_DP<89>")
		)
		(pad "G34" smd circle
			(at 8.549894 -17.100042)
			(size 0.4572 0.4572)
			(layers "F.Cu" "F.Mask" "F.Paste")
			(net "GND")
		)
		(pad "G35" smd circle
			(at 9.500108 -17.100042)
			(size 0.4572 0.4572)
			(layers "F.Cu" "F.Mask" "F.Paste")
			(net "P5E_PEX2_STN5_TX_DP<91>")
		)
		(pad "G36" smd circle
			(at 10.450068 -17.100042)
			(size 0.4572 0.4572)
			(layers "F.Cu" "F.Mask" "F.Paste")
			(net "GND")
		)
		(pad "G37" smd circle
			(at 11.400028 -17.100042)
			(size 0.4572 0.4572)
			(layers "F.Cu" "F.Mask" "F.Paste")
			(net "P5E_PEX2_STN5_TX_DP<93>")
		)
		(pad "G38" smd circle
			(at 12.349988 -17.100042)
			(size 0.4572 0.4572)
			(layers "F.Cu" "F.Mask" "F.Paste")
			(net "GND")
		)
		(pad "G39" smd circle
			(at 13.299948 -17.100042)
			(size 0.4572 0.4572)
			(layers "F.Cu" "F.Mask" "F.Paste")
			(net "P5E_PEX2_STN5_TX_DP<95>")
		)
		(pad "G40" smd circle
			(at 14.249908 -17.100042)
			(size 0.4572 0.4572)
			(layers "F.Cu" "F.Mask" "F.Paste")
			(net "GND")
		)
		(pad "G41" smd circle
			(at 15.200122 -17.100042)
			(size 0.4572 0.4572)
			(layers "F.Cu" "F.Mask" "F.Paste")
			(net "P5E_PEX2_STN4_TX_DP<78>")
		)
		(pad "G42" smd circle
			(at 16.150082 -17.100042)
			(size 0.4572 0.4572)
			(layers "F.Cu" "F.Mask" "F.Paste")
			(net "GND")
		)
		(pad "G43" smd circle
			(at 17.100042 -17.100042)
			(size 0.4572 0.4572)
			(layers "F.Cu" "F.Mask" "F.Paste")
			(net "P5E_PEX2_STN4_TX_DP<76>")
		)
		(pad "G44" smd circle
			(at 18.050002 -17.100042)
			(size 0.4572 0.4572)
			(layers "F.Cu" "F.Mask" "F.Paste")
			(net "GND")
		)
		(pad "G45" smd circle
			(at 18.999962 -17.100042)
			(size 0.4572 0.4572)
			(layers "F.Cu" "F.Mask" "F.Paste")
			(net "P5E_PEX2_STN4_TX_DP<74>")
		)
		(pad "G46" smd circle
			(at 19.949922 -17.100042)
			(size 0.4572 0.4572)
			(layers "F.Cu" "F.Mask" "F.Paste")
			(net "GND")
		)
		(pad "G47" smd circle
			(at 20.899882 -17.100042)
			(size 0.4572 0.4572)
			(layers "F.Cu" "F.Mask" "F.Paste")
			(net "P5E_PEX2_STN4_TX_DP<72>")
		)
		(pad "G48" smd circle
			(at 21.850096 -17.100042)
			(size 0.4572 0.4572)
			(layers "F.Cu" "F.Mask" "F.Paste")
			(net "GND")
		)
		(pad "G49" smd circle
			(at 22.800056 -17.100042)
			(size 0.4572 0.4572)
			(layers "F.Cu" "F.Mask" "F.Paste")
			(net "GND")
		)
		(pad "H1" smd circle
			(at -22.800056 -16.150082)
			(size 0.4572 0.4572)
			(layers "F.Cu" "F.Mask" "F.Paste")
			(net "P5E_PEX2_STN7_TX_DN<121>")
		)
		(pad "H2" smd circle
			(at -21.850096 -16.150082)
			(size 0.4572 0.4572)
			(layers "F.Cu" "F.Mask" "F.Paste")
			(net "P5E_PEX2_STN7_TX_DP<121>")
		)
		(pad "H3" smd circle
			(at -20.899882 -16.150082)
			(size 0.4572 0.4572)
			(layers "F.Cu" "F.Mask" "F.Paste")
			(net "GND")
		)
		(pad "H4" smd circle
			(at -19.949922 -16.150082)
			(size 0.4572 0.4572)
			(layers "F.Cu" "F.Mask" "F.Paste")
			(net "P5E_PEX2_STN7_TX_DN<124>")
		)
		(pad "H5" smd circle
			(at -18.999962 -16.150082)
			(size 0.4572 0.4572)
			(layers "F.Cu" "F.Mask" "F.Paste")
			(net "GND")
		)
		(pad "H6" smd circle
			(at -18.050002 -16.150082)
			(size 0.4572 0.4572)
			(layers "F.Cu" "F.Mask" "F.Paste")
			(net "P5E_PEX2_STN7_TX_DN<126>")
		)
		(pad "H7" smd circle
			(at -17.100042 -16.150082)
			(size 0.4572 0.4572)
			(layers "F.Cu" "F.Mask" "F.Paste")
			(net "GND")
		)
	)
)
